(kicad_pcb
	(version 20260206)
	(generator "pcbnew")
	(generator_version "10.0")
	(general
		(thickness 1.6)
		(legacy_teardrops no)
	)
	(paper "A4")
	(title_block
		(title "Bryce Canyon_R.DPB_16317-1_OCP.brd")
		(comment 1 "Bryce Canyon / footprints 533-539 of 2099")
	)
	(layers
		(0 "F.Cu" signal "TOP")
		(4 "In1.Cu" signal "L2GND")
		(6 "In2.Cu" signal "L3")
		(8 "In3.Cu" signal "L4VCC")
		(10 "In4.Cu" signal "L5VCC")
		(12 "In5.Cu" signal "L6")
		(14 "In6.Cu" signal "L7GND")
		(2 "B.Cu" signal "BOTTOM")
		(9 "F.Adhes" user "F.Adhesive")
		(11 "B.Adhes" user "B.Adhesive")
		(13 "F.Paste" user "Package Geometry/Pastemask Top")
		(15 "B.Paste" user "Package Geometry/Pastemask Bottom")
		(5 "F.SilkS" user "Ref Des/Silkscreen Top")
		(7 "B.SilkS" user "Ref Des/Silkscreen Bottom")
		(1 "F.Mask" user "Board Geometry/Soldermask Top")
		(3 "B.Mask" user "Board Geometry/Soldermask Bottom")
		(17 "Dwgs.User" user "User.Drawings")
		(19 "Cmts.User" user "User.Comments")
		(21 "Eco1.User" user "User.Eco1")
		(23 "Eco2.User" user "User.Eco2")
		(25 "Edge.Cuts" user "Board Geometry/Outline")
		(27 "Margin" user)
		(31 "F.CrtYd" user "Package Geometry/Place Bound Top")
		(29 "B.CrtYd" user "Package Geometry/Place Bound Bottom")
		(35 "F.Fab" user "Ref Des/Assembly Top")
		(33 "B.Fab" user "Ref Des/Assembly Bottom")
	)
	(footprint ""
		(layer "F.Cu")
		(at 27.801824 -223.027748 90)
		(property "Reference" "C625"
			(at 0 0 90)
			(layer "F.SilkS")
			(hide yes)
			(effects
				(font
					(size 1.27 1.27)
				)
			)
		)
		(property "Value" "SCD1U16V2KX-3GP"
			(at 1.1811 -2.7051 90)
			(unlocked yes)
			(layer "F.Fab")
			(hide yes)
			(effects
				(font
					(size 1.016 1.016)
					(thickness 0.1524)
				)
			)
		)
		(property "Device Type" "C402H22"
			(at 1.1811 -4.2291 90)
			(unlocked yes)
			(layer "F.Fab")
			(hide yes)
			(effects
				(font
					(size 1.016 1.016)
					(thickness 0.1524)
				)
			)
		)
		(duplicate_pad_numbers_are_jumpers no)
		(fp_rect
			(start -0.4318 0.9525)
			(end 0.4318 -0.9525)
			(stroke
				(width 0)
				(type default)
			)
			(fill no)
			(layer "F.CrtYd")
		)
		(fp_rect
			(start -0.4318 0.9525)
			(end 0.4318 -0.9525)
			(stroke
				(width 0)
				(type default)
			)
			(fill no)
			(layer "F.Fab")
		)
		(pad "1" smd custom
			(at 0 -0.4445 90)
			(size 0.1524 0.1524)
			(layers "F.Cu" "F.Mask" "F.Paste")
			(net "P5V_B_1_VBST_RC")
			(options
				(clearance outline)
				(anchor circle)
			)
			(primitives
				(gr_poly
					(pts
						(arc
							(start 0.3048 -0.2032)
							(mid 0.275042 -0.275042)
							(end 0.2032 -0.3048)
						)
						(arc
							(start -0.2032 -0.3048)
							(mid -0.275042 -0.275042)
							(end -0.3048 -0.2032)
						)
						(arc
							(start -0.3048 0.2032)
							(mid -0.275042 0.275042)
							(end -0.2032 0.3048)
						)
						(arc
							(start 0.2032 0.3048)
							(mid 0.275042 0.275042)
							(end 0.3048 0.2032)
						)
					)
					(width 0)
					(fill yes)
				)
			)
		)
		(pad "2" smd custom
			(at 0 0.4445 90)
			(size 0.1524 0.1524)
			(layers "F.Cu" "F.Mask" "F.Paste")
			(net "P5V_B_1_LL")
			(options
				(clearance outline)
				(anchor circle)
			)
			(primitives
				(gr_poly
					(pts
						(arc
							(start 0.3048 -0.2032)
							(mid 0.275042 -0.275042)
							(end 0.2032 -0.3048)
						)
						(arc
							(start -0.2032 -0.3048)
							(mid -0.275042 -0.275042)
							(end -0.3048 -0.2032)
						)
						(arc
							(start -0.3048 0.2032)
							(mid -0.275042 0.275042)
							(end -0.2032 0.3048)
						)
						(arc
							(start 0.2032 0.3048)
							(mid 0.275042 0.275042)
							(end 0.3048 0.2032)
						)
					)
					(width 0)
					(fill yes)
				)
			)
		)
	)
	(footprint ""
		(layer "F.Cu")
		(at 222.3008 -301.8536 90)
		(property "Reference" "C709"
			(at 0 0 90)
			(layer "F.SilkS")
			(hide yes)
			(effects
				(font
					(size 1.27 1.27)
				)
			)
		)
		(property "Value" "SCD1U16V2KX-3GP"
			(at 1.1811 -2.7051 90)
			(unlocked yes)
			(layer "F.Fab")
			(hide yes)
			(effects
				(font
					(size 1.016 1.016)
					(thickness 0.1524)
				)
			)
		)
		(property "Device Type" "C402H22"
			(at 1.1811 -4.2291 90)
			(unlocked yes)
			(layer "F.Fab")
			(hide yes)
			(effects
				(font
					(size 1.016 1.016)
					(thickness 0.1524)
				)
			)
		)
		(duplicate_pad_numbers_are_jumpers no)
		(fp_rect
			(start -0.4318 0.9525)
			(end 0.4318 -0.9525)
			(stroke
				(width 0)
				(type default)
			)
			(fill no)
			(layer "F.CrtYd")
		)
		(fp_rect
			(start -0.4318 0.9525)
			(end 0.4318 -0.9525)
			(stroke
				(width 0)
				(type default)
			)
			(fill no)
			(layer "F.Fab")
		)
		(pad "1" smd custom
			(at 0 -0.4445 90)
			(size 0.1524 0.1524)
			(layers "F.Cu" "F.Mask" "F.Paste")
			(net "FANTACH_A_OE")
			(options
				(clearance outline)
				(anchor circle)
			)
			(primitives
				(gr_poly
					(pts
						(arc
							(start 0.3048 -0.2032)
							(mid 0.275042 -0.275042)
							(end 0.2032 -0.3048)
						)
						(arc
							(start -0.2032 -0.3048)
							(mid -0.275042 -0.275042)
							(end -0.3048 -0.2032)
						)
						(arc
							(start -0.3048 0.2032)
							(mid -0.275042 0.275042)
							(end -0.2032 0.3048)
						)
						(arc
							(start 0.2032 0.3048)
							(mid 0.275042 0.275042)
							(end 0.3048 0.2032)
						)
					)
					(width 0)
					(fill yes)
				)
			)
		)
		(pad "2" smd custom
			(at 0 0.4445 90)
			(size 0.1524 0.1524)
			(layers "F.Cu" "F.Mask" "F.Paste")
			(net "GND")
			(options
				(clearance outline)
				(anchor circle)
			)
			(primitives
				(gr_poly
					(pts
						(arc
							(start 0.3048 -0.2032)
							(mid 0.275042 -0.275042)
							(end 0.2032 -0.3048)
						)
						(arc
							(start -0.2032 -0.3048)
							(mid -0.275042 -0.275042)
							(end -0.3048 -0.2032)
						)
						(arc
							(start -0.3048 0.2032)
							(mid -0.275042 0.275042)
							(end -0.2032 0.3048)
						)
						(arc
							(start 0.2032 0.3048)
							(mid 0.275042 0.275042)
							(end 0.3048 0.2032)
						)
					)
					(width 0)
					(fill yes)
				)
			)
		)
	)
	(footprint ""
		(layer "F.Cu")
		(at 333.1718 -17.1196 180)
		(property "Reference" "R776"
			(at 0 0 180)
			(layer "F.SilkS")
			(hide yes)
			(effects
				(font
					(size 1.27 1.27)
				)
			)
		)
		(property "Value" "200KR2F-L-GP"
			(at 0.064008 -3.993896 180)
			(unlocked yes)
			(layer "F.Fab")
			(hide yes)
			(effects
				(font
					(size 1.016 1.016)
					(thickness 0.1524)
				)
			)
		)
		(property "Device Type" "R402H16"
			(at 0.064008 -5.517896 180)
			(unlocked yes)
			(layer "F.Fab")
			(hide yes)
			(effects
				(font
					(size 1.016 1.016)
					(thickness 0.1524)
				)
			)
		)
		(duplicate_pad_numbers_are_jumpers no)
		(fp_line
			(start 0.508 -0.9398)
			(end -0.508 -0.9398)
			(stroke
				(width 0.1524)
				(type default)
			)
			(layer "F.SilkS")
		)
		(fp_line
			(start -0.508 -0.9398)
			(end -0.508 0.9398)
			(stroke
				(width 0.1524)
				(type default)
			)
			(layer "F.SilkS")
		)
		(fp_rect
			(start -0.508 0.9398)
			(end 0.508 -0.9398)
			(stroke
				(width 0)
				(type default)
			)
			(fill no)
			(layer "F.CrtYd")
		)
		(fp_rect
			(start -0.508 0.9398)
			(end 0.508 -0.9398)
			(stroke
				(width 0)
				(type default)
			)
			(fill no)
			(layer "F.Fab")
		)
		(pad "1" smd custom
			(at 0 -0.4445 180)
			(size 0.1397 0.1397)
			(layers "F.Cu" "F.Mask" "F.Paste")
			(net "SW_HDD_R30")
			(options
				(clearance outline)
				(anchor circle)
			)
			(primitives
				(gr_poly
					(pts
						(arc
							(start -0.1778 -0.2794)
							(mid -0.249642 -0.249642)
							(end -0.2794 -0.1778)
						)
						(arc
							(start -0.2794 0.1778)
							(mid -0.249642 0.249642)
							(end -0.1778 0.2794)
						)
						(arc
							(start 0.1778 0.2794)
							(mid 0.249642 0.249642)
							(end 0.2794 0.1778)
						)
						(arc
							(start 0.2794 -0.1778)
							(mid 0.249642 -0.249642)
							(end 0.1778 -0.2794)
						)
					)
					(width 0)
					(fill yes)
				)
			)
		)
		(pad "2" smd custom
			(at 0 0.4445 180)
			(size 0.1397 0.1397)
			(layers "F.Cu" "F.Mask" "F.Paste")
			(net "SW_HDD_N30")
			(options
				(clearance outline)
				(anchor circle)
			)
			(primitives
				(gr_poly
					(pts
						(arc
							(start -0.1778 -0.2794)
							(mid -0.249642 -0.249642)
							(end -0.2794 -0.1778)
						)
						(arc
							(start -0.2794 0.1778)
							(mid -0.249642 0.249642)
							(end -0.1778 0.2794)
						)
						(arc
							(start 0.1778 0.2794)
							(mid 0.249642 0.249642)
							(end 0.2794 0.1778)
						)
						(arc
							(start 0.2794 -0.1778)
							(mid 0.249642 -0.249642)
							(end 0.1778 -0.2794)
						)
					)
					(width 0)
					(fill yes)
				)
			)
		)
	)
	(footprint ""
		(layer "F.Cu")
		(at 49.29886 -119.453406 -90)
		(property "Reference" "R1119"
			(at 0 0 270)
			(layer "F.SilkS")
			(hide yes)
			(effects
				(font
					(size 1.27 1.27)
				)
			)
		)
		(property "Value" "10KR2F-2-GP"
			(at 0.064008 -3.993896 270)
			(unlocked yes)
			(layer "F.Fab")
			(hide yes)
			(effects
				(font
					(size 1.016 1.016)
					(thickness 0.1524)
				)
			)
		)
		(property "Device Type" "R402H16"
			(at 0.064008 -5.517896 270)
			(unlocked yes)
			(layer "F.Fab")
			(hide yes)
			(effects
				(font
					(size 1.016 1.016)
					(thickness 0.1524)
				)
			)
		)
		(duplicate_pad_numbers_are_jumpers no)
		(fp_line
			(start -0.508 -0.9398)
			(end -0.508 0.9398)
			(stroke
				(width 0.1524)
				(type default)
			)
			(layer "F.SilkS")
		)
		(fp_line
			(start 0.508 -0.9398)
			(end -0.508 -0.9398)
			(stroke
				(width 0.1524)
				(type default)
			)
			(layer "F.SilkS")
		)
		(fp_rect
			(start -0.508 0.9398)
			(end 0.508 -0.9398)
			(stroke
				(width 0)
				(type default)
			)
			(fill no)
			(layer "F.CrtYd")
		)
		(fp_rect
			(start -0.508 0.9398)
			(end 0.508 -0.9398)
			(stroke
				(width 0)
				(type default)
			)
			(fill no)
			(layer "F.Fab")
		)
		(pad "1" smd custom
			(at 0 -0.4445 270)
			(size 0.1397 0.1397)
			(layers "F.Cu" "F.Mask" "F.Paste")
			(net "P5V_B_2_EN_R")
			(options
				(clearance outline)
				(anchor circle)
			)
			(primitives
				(gr_poly
					(pts
						(arc
							(start -0.1778 -0.2794)
							(mid -0.249642 -0.249642)
							(end -0.2794 -0.1778)
						)
						(arc
							(start -0.2794 0.1778)
							(mid -0.249642 0.249642)
							(end -0.1778 0.2794)
						)
						(arc
							(start 0.1778 0.2794)
							(mid 0.249642 0.249642)
							(end 0.2794 0.1778)
						)
						(arc
							(start 0.2794 -0.1778)
							(mid 0.249642 -0.249642)
							(end 0.1778 -0.2794)
						)
					)
					(width 0)
					(fill yes)
				)
			)
		)
		(pad "2" smd custom
			(at 0 0.4445 270)
			(size 0.1397 0.1397)
			(layers "F.Cu" "F.Mask" "F.Paste")
			(net "GND")
			(options
				(clearance outline)
				(anchor circle)
			)
			(primitives
				(gr_poly
					(pts
						(arc
							(start -0.1778 -0.2794)
							(mid -0.249642 -0.249642)
							(end -0.2794 -0.1778)
						)
						(arc
							(start -0.2794 0.1778)
							(mid -0.249642 0.249642)
							(end -0.1778 0.2794)
						)
						(arc
							(start 0.1778 0.2794)
							(mid 0.249642 0.249642)
							(end 0.2794 0.1778)
						)
						(arc
							(start 0.2794 -0.1778)
							(mid 0.249642 -0.249642)
							(end 0.1778 -0.2794)
						)
					)
					(width 0)
					(fill yes)
				)
			)
		)
	)
	(footprint ""
		(layer "F.Cu")
		(at 83.566 -19.558 180)
		(property "Reference" "Q131"
			(at 0 0 180)
			(layer "F.SilkS")
			(hide yes)
			(effects
				(font
					(size 1.27 1.27)
				)
			)
		)
		(property "Value" "2N7002KDW-GP"
			(at -2.3622 -8.2042 180)
			(unlocked yes)
			(layer "F.Fab")
			(hide yes)
			(effects
				(font
					(size 1.016 1.016)
					(thickness 0.1524)
				)
			)
		)
		(property "Device Type" "SOT-363H44"
			(at -2.3622 -10.1092 180)
			(unlocked yes)
			(layer "F.Fab")
			(hide yes)
			(effects
				(font
					(size 1.016 1.016)
					(thickness 0.1524)
				)
			)
		)
		(duplicate_pad_numbers_are_jumpers no)
		(fp_line
			(start 1.4478 1.7018)
			(end 1.4478 -1.7018)
			(stroke
				(width 0.1524)
				(type default)
			)
			(layer "F.SilkS")
		)
		(fp_line
			(start 1.4478 -1.7018)
			(end -1.4478 -1.7018)
			(stroke
				(width 0.1524)
				(type default)
			)
			(layer "F.SilkS")
		)
		(fp_line
			(start -1.27 1.524)
			(end -1.27 0.6604)
			(stroke
				(width 0.4826)
				(type default)
			)
			(layer "F.SilkS")
		)
		(fp_line
			(start -1.4478 1.7018)
			(end 1.4478 1.7018)
			(stroke
				(width 0.1524)
				(type default)
			)
			(layer "F.SilkS")
		)
		(fp_line
			(start -1.4478 -1.7018)
			(end -1.4478 1.7018)
			(stroke
				(width 0.1524)
				(type default)
			)
			(layer "F.SilkS")
		)
		(fp_poly
			(pts
				(xy -1.524 -1.778) (xy 1.524 -1.778) (xy 1.524 1.778) (xy -1.524 1.778)
			)
			(stroke
				(width 0)
				(type default)
			)
			(fill no)
			(layer "F.CrtYd")
		)
		(fp_poly
			(pts
				(xy -1.524 -1.778) (xy 1.524 -1.778) (xy 1.524 1.778) (xy -1.524 1.778)
			)
			(stroke
				(width 0)
				(type default)
			)
			(fill no)
			(layer "F.Fab")
		)
		(pad "1" smd rect
			(at -0.65024 0.9398 180)
			(size 0.4064 1.016)
			(layers "F.Cu" "F.Mask" "F.Paste")
			(net "GND")
		)
		(pad "2" smd rect
			(at 0 0.9398 180)
			(size 0.4064 1.016)
			(layers "F.Cu" "F.Mask" "F.Paste")
			(net "SW_PWR_R_HDD26")
		)
		(pad "3" smd rect
			(at 0.65024 0.9398 180)
			(size 0.4064 1.016)
			(layers "F.Cu" "F.Mask" "F.Paste")
			(net "SW_HDD_P26")
		)
		(pad "4" smd rect
			(at 0.65024 -0.9398 180)
			(size 0.4064 1.016)
			(layers "F.Cu" "F.Mask" "F.Paste")
			(net "GND")
		)
		(pad "5" smd rect
			(at 0 -0.9398 180)
			(size 0.4064 1.016)
			(layers "F.Cu" "F.Mask" "F.Paste")
			(net "SW_HDD_G26")
		)
		(pad "6" smd rect
			(at -0.65024 -0.9398 180)
			(size 0.4064 1.016)
			(layers "F.Cu" "F.Mask" "F.Paste")
			(net "SW_HDD_R26")
		)
	)
	(footprint ""
		(layer "F.Cu")
		(at 353.184714 -15.219426 -90)
		(property "Reference" "C431"
			(at 0 0 270)
			(layer "F.SilkS")
			(hide yes)
			(effects
				(font
					(size 1.27 1.27)
				)
			)
		)
		(property "Value" "SCD01U16V1KX-GP"
			(at -2.8321 -1.7399 270)
			(unlocked yes)
			(layer "F.Fab")
			(hide yes)
			(effects
				(font
					(size 1.016 1.016)
					(thickness 0.1524)
				)
			)
		)
		(property "Device Type" "C0201H13"
			(at -2.8321 -3.2639 270)
			(unlocked yes)
			(layer "F.Fab")
			(hide yes)
			(effects
				(font
					(size 1.016 1.016)
					(thickness 0.1524)
				)
			)
		)
		(duplicate_pad_numbers_are_jumpers no)
		(fp_rect
			(start -0.2794 0.6477)
			(end 0.2794 -0.6477)
			(stroke
				(width 0)
				(type default)
			)
			(fill no)
			(layer "F.CrtYd")
		)
		(fp_rect
			(start -0.2794 0.6477)
			(end 0.2794 -0.6477)
			(stroke
				(width 0)
				(type default)
			)
			(fill no)
			(layer "F.Fab")
		)
		(pad "1" smd custom
			(at 0 -0.2794 270)
			(size 0.0762 0.0762)
			(layers "F.Cu" "F.Mask" "F.Paste")
			(net "SAS_HDD_RX_N31")
			(options
				(clearance outline)
				(anchor circle)
			)
			(primitives
				(gr_poly
					(pts
						(arc
							(start 0.1524 -0.127)
							(mid 0.137521 -0.162921)
							(end 0.1016 -0.1778)
						)
						(arc
							(start -0.1016 -0.1778)
							(mid -0.137521 -0.162921)
							(end -0.1524 -0.127)
						)
						(arc
							(start -0.1524 0.127)
							(mid -0.137521 0.162921)
							(end -0.1016 0.1778)
						)
						(arc
							(start 0.1016 0.1778)
							(mid 0.137521 0.162921)
							(end 0.1524 0.127)
						)
					)
					(width 0)
					(fill yes)
				)
			)
		)
		(pad "2" smd custom
			(at 0 0.2794 270)
			(size 0.0762 0.0762)
			(layers "F.Cu" "F.Mask" "F.Paste")
			(net "PHY_SCC_B_TO_DRV_B_31_DN")
			(options
				(clearance outline)
				(anchor circle)
			)
			(primitives
				(gr_poly
					(pts
						(arc
							(start 0.1524 -0.127)
							(mid 0.137521 -0.162921)
							(end 0.1016 -0.1778)
						)
						(arc
							(start -0.1016 -0.1778)
							(mid -0.137521 -0.162921)
							(end -0.1524 -0.127)
						)
						(arc
							(start -0.1524 0.127)
							(mid -0.137521 0.162921)
							(end -0.1016 0.1778)
						)
						(arc
							(start 0.1016 0.1778)
							(mid 0.137521 0.162921)
							(end 0.1524 0.127)
						)
					)
					(width 0)
					(fill yes)
				)
			)
		)
	)
	(footprint ""
		(layer "F.Cu")
		(at 147.040092 -214.91702 90)
		(property "Reference" "Q247"
			(at 0 0 90)
			(layer "F.SilkS")
			(hide yes)
			(effects
				(font
					(size 1.27 1.27)
				)
			)
		)
		(property "Value" "SSM3K324R-GP"
			(at 0.127 -8.9662 90)
			(unlocked yes)
			(layer "F.Fab")
			(hide yes)
			(effects
				(font
					(size 1.016 1.016)
					(thickness 0.1524)
				)
			)
		)
		(property "Device Type" "SOT23DGS2D4H35"
			(at 0.127 -10.4902 90)
			(unlocked yes)
			(layer "F.Fab")
			(hide yes)
			(effects
				(font
					(size 1.016 1.016)
					(thickness 0.1524)
				)
			)
		)
		(duplicate_pad_numbers_are_jumpers no)
		(fp_line
			(start 1.651 -1.778)
			(end -1.651 -1.778)
			(stroke
				(width 0.1524)
				(type default)
			)
			(layer "F.SilkS")
		)
		(fp_line
			(start -1.651 -1.778)
			(end -1.651 1.778)
			(stroke
				(width 0.1524)
				(type default)
			)
			(layer "F.SilkS")
		)
		(fp_line
			(start 1.651 1.778)
			(end 1.651 -1.778)
			(stroke
				(width 0.1524)
				(type default)
			)
			(layer "F.SilkS")
		)
		(fp_line
			(start -1.651 1.778)
			(end 1.651 1.778)
			(stroke
				(width 0.1524)
				(type default)
			)
			(layer "F.SilkS")
		)
		(fp_poly
			(pts
				(xy -1.778 1.8796) (xy -1.778 -1.8796) (xy 1.778 -1.8796) (xy 1.778 1.8796)
			)
			(stroke
				(width 0)
				(type default)
			)
			(fill no)
			(layer "F.CrtYd")
		)
		(fp_poly
			(pts
				(xy -1.778 1.8796) (xy -1.778 -1.8796) (xy 1.778 -1.8796) (xy 1.778 1.8796)
			)
			(stroke
				(width 0)
				(type default)
			)
			(fill no)
			(layer "F.Fab")
		)
		(pad "D" smd custom
			(at 0 -0.9525 90)
			(size 0.1905 0.1905)
			(layers "F.Cu" "F.Mask" "F.Paste")
			(net "DRV_ACT_4_N")
			(options
				(clearance outline)
				(anchor circle)
			)
			(primitives
				(gr_poly
					(pts
						(arc
							(start -0.1778 0.5715)
							(mid -0.321484 0.511984)
							(end -0.381 0.3683)
						)
						(arc
							(start -0.381 -0.3683)
							(mid -0.321484 -0.511984)
							(end -0.1778 -0.5715)
						)
						(arc
							(start 0.1778 -0.5715)
							(mid 0.321484 -0.511984)
							(end 0.381 -0.3683)
						)
						(arc
							(start 0.381 0.3683)
							(mid 0.321484 0.511984)
							(end 0.1778 0.5715)
						)
					)
					(width 0)
					(fill yes)
				)
			)
		)
		(pad "G" smd custom
			(at -0.98425 0.9525 90)
			(size 0.1905 0.1905)
			(layers "F.Cu" "F.Mask" "F.Paste")
			(net "DRIVE_B_4_ACT")
			(options
				(clearance outline)
				(anchor circle)
			)
			(primitives
				(gr_poly
					(pts
						(arc
							(start -0.1778 0.5715)
							(mid -0.321484 0.511984)
							(end -0.381 0.3683)
						)
						(arc
							(start -0.381 -0.3683)
							(mid -0.321484 -0.511984)
							(end -0.1778 -0.5715)
						)
						(arc
							(start 0.1778 -0.5715)
							(mid 0.321484 -0.511984)
							(end 0.381 -0.3683)
						)
						(arc
							(start 0.381 0.3683)
							(mid 0.321484 0.511984)
							(end 0.1778 0.5715)
						)
					)
					(width 0)
					(fill yes)
				)
			)
		)
		(pad "S" smd custom
			(at 0.98425 0.9525 90)
			(size 0.1905 0.1905)
			(layers "F.Cu" "F.Mask" "F.Paste")
			(net "GND")
			(options
				(clearance outline)
				(anchor circle)
			)
			(primitives
				(gr_poly
					(pts
						(arc
							(start -0.1778 0.5715)
							(mid -0.321484 0.511984)
							(end -0.381 0.3683)
						)
						(arc
							(start -0.381 -0.3683)
							(mid -0.321484 -0.511984)
							(end -0.1778 -0.5715)
						)
						(arc
							(start 0.1778 -0.5715)
							(mid 0.321484 -0.511984)
							(end 0.381 -0.3683)
						)
						(arc
							(start 0.381 0.3683)
							(mid 0.321484 0.511984)
							(end 0.1778 0.5715)
						)
					)
					(width 0)
					(fill yes)
				)
			)
		)
	)
)
